(kicad_pcb
	(version 20260206)
	(generator "pcbnew")
	(generator_version "10.0")
	(general
		(thickness 1.6)
		(legacy_teardrops no)
	)
	(paper "A4")
	(title_block
		(title "Wiwynn_Tioga_Pass_MB.brd")
		(comment 1 "Tioga Pass / footprint 2254 of 4770 (U5D1), pads 3047-3151 of 3647")
	)
	(layers
		(0 "F.Cu" signal "TOP")
		(4 "In1.Cu" signal "L2GND")
		(6 "In2.Cu" signal "L3")
		(8 "In3.Cu" signal "L4GND")
		(10 "In4.Cu" signal "L5")
		(12 "In5.Cu" signal "L6GND")
		(14 "In6.Cu" signal "L7VCC")
		(16 "In7.Cu" signal "L8VCC")
		(18 "In8.Cu" signal "L9GND")
		(20 "In9.Cu" signal "L10")
		(22 "In10.Cu" signal "L11GND")
		(24 "In11.Cu" signal "L12")
		(26 "In12.Cu" signal "L13GND")
		(2 "B.Cu" signal "BOTTOM")
		(9 "F.Adhes" user "F.Adhesive")
		(11 "B.Adhes" user "B.Adhesive")
		(13 "F.Paste" user "Package Geometry/Pastemask Top")
		(15 "B.Paste" user "Package Geometry/Pastemask Bottom")
		(5 "F.SilkS" user "Ref Des/Silkscreen Top")
		(7 "B.SilkS" user "Ref Des/Silkscreen Bottom")
		(1 "F.Mask" user "Board Geometry/Soldermask Top")
		(3 "B.Mask" user "Board Geometry/Soldermask Bottom")
		(17 "Dwgs.User" user "User.Drawings")
		(19 "Cmts.User" user "User.Comments")
		(21 "Eco1.User" user "User.Eco1")
		(23 "Eco2.User" user "User.Eco2")
		(25 "Edge.Cuts" user "Board Geometry/Outline")
		(27 "Margin" user)
		(31 "F.CrtYd" user "Package Geometry/Place Bound Top")
		(29 "B.CrtYd" user "Package Geometry/Place Bound Bottom")
		(35 "F.Fab" user "Ref Des/Assembly Top")
		(33 "B.Fab" user "Ref Des/Assembly Bottom")
	)
	(footprint ""
		(layer "F.Cu")
		(at 270.000222 -76.550012 180)
		(property "Reference" "U5D1"
			(at 19.124422 31.601918 0)
			(unlocked yes)
			(layer "F.SilkS")
			(effects
				(font
					(size 0.7874 0.5842)
					(thickness 0.1524)
				)
			)
		)
		(property "Value" ""
			(at 0 0 180)
			(layer "F.Fab")
			(effects
				(font
					(size 1.27 1.27)
				)
			)
		)
		(duplicate_pad_numbers_are_jumpers no)
		(pad "F71" smd custom
			(at 24.373078 -24.426672)
			(size 0.10795 0.10795)
			(layers "F.Cu" "F.Mask" "F.Paste")
			(net "M_B_DQ<27>")
			(options
				(clearance outline)
				(anchor circle)
			)
			(primitives
				(gr_poly
					(pts
						(arc
							(start 0.2159 -0.0381)
							(mid 0 -0.254)
							(end -0.2159 -0.0381)
						)
						(arc
							(start -0.2159 0.0381)
							(mid 0 0.254)
							(end 0.2159 0.0381)
						)
					)
					(width 0)
					(fill yes)
				)
			)
		)
		(pad "F73" smd circle
			(at 26.090118 -24.426672)
			(size 0.4318 0.4318)
			(layers "F.Cu" "F.Mask" "F.Paste")
			(net "M_B_DQS_DP<3>")
		)
		(pad "F75" smd circle
			(at 27.806904 -24.426672)
			(size 0.4318 0.4318)
			(layers "F.Cu" "F.Mask" "F.Paste")
			(net "M_B_DQ<28>")
		)
		(pad "F77" smd circle
			(at 29.523944 -24.426672)
			(size 0.4318 0.4318)
			(layers "F.Cu" "F.Mask" "F.Paste")
			(net "M_B_DQ<18>")
		)
		(pad "F79" smd circle
			(at 31.240984 -24.426672)
			(size 0.4318 0.4318)
			(layers "F.Cu" "F.Mask" "F.Paste")
			(net "M_B_DQS_DP<11>")
		)
		(pad "F81" smd circle
			(at 32.958024 -24.426672)
			(size 0.4318 0.4318)
			(layers "F.Cu" "F.Mask" "F.Paste")
			(net "M_B_DQ<20>")
		)
		(pad "F83" smd custom
			(at 34.675064 -24.426672 270)
			(size 0.10795 0.10795)
			(layers "F.Cu" "F.Mask" "F.Paste")
			(net "TP_CPU0_RSVD_276")
			(options
				(clearance outline)
				(anchor circle)
			)
			(primitives
				(gr_poly
					(pts
						(arc
							(start 0.2159 -0.0381)
							(mid 0 -0.254)
							(end -0.2159 -0.0381)
						)
						(arc
							(start -0.2159 0.0381)
							(mid 0 0.254)
							(end 0.2159 0.0381)
						)
					)
					(width 0)
					(fill yes)
				)
			)
		)
		(pad "G2" smd custom
			(at -36.392104 -22.131274 90)
			(size 0.10795 0.10795)
			(layers "F.Cu" "F.Mask" "F.Paste")
			(net "TP_CPU0_RSVD_275")
			(options
				(clearance outline)
				(anchor circle)
			)
			(primitives
				(gr_poly
					(pts
						(arc
							(start 0.2159 -0.0381)
							(mid 0 -0.254)
							(end -0.2159 -0.0381)
						)
						(arc
							(start -0.2159 0.0381)
							(mid 0 0.254)
							(end 0.2159 0.0381)
						)
					)
					(width 0)
					(fill yes)
				)
			)
		)
		(pad "G4" smd circle
			(at -34.675064 -22.131274)
			(size 0.4318 0.4318)
			(layers "F.Cu" "F.Mask" "F.Paste")
			(net "GND")
		)
		(pad "G6" smd circle
			(at -32.958024 -22.131274)
			(size 0.4318 0.4318)
			(layers "F.Cu" "F.Mask" "F.Paste")
			(net "UPI_CPU0_CPU1_P1P1_DN<15>")
		)
		(pad "G8" smd circle
			(at -31.240984 -22.131274)
			(size 0.4318 0.4318)
			(layers "F.Cu" "F.Mask" "F.Paste")
			(net "GND")
		)
		(pad "G10" smd circle
			(at -29.523944 -22.131274)
			(size 0.4318 0.4318)
			(layers "F.Cu" "F.Mask" "F.Paste")
			(net "UPI_CPU0_CPU1_P1P1_DN<10>")
		)
		(pad "G12" smd circle
			(at -27.806904 -22.131274)
			(size 0.4318 0.4318)
			(layers "F.Cu" "F.Mask" "F.Paste")
			(net "UPI_CPU0_CPU1_P1P1_DP<9>")
		)
		(pad "G14" smd circle
			(at -26.090118 -22.131274)
			(size 0.4318 0.4318)
			(layers "F.Cu" "F.Mask" "F.Paste")
			(net "UPI_CPU0_CPU1_P1P1_DN<8>")
		)
		(pad "G16" smd circle
			(at -24.373078 -22.131274)
			(size 0.4318 0.4318)
			(layers "F.Cu" "F.Mask" "F.Paste")
			(net "UPI_CPU0_CPU1_P1P1_DP<5>")
		)
		(pad "G18" smd circle
			(at -22.656038 -22.131274)
			(size 0.4318 0.4318)
			(layers "F.Cu" "F.Mask" "F.Paste")
			(net "UPI_CPU0_CPU1_P1P1_DN<3>")
		)
		(pad "G20" smd circle
			(at -20.938998 -22.131274)
			(size 0.4318 0.4318)
			(layers "F.Cu" "F.Mask" "F.Paste")
			(net "UPI_CPU0_CPU1_P1P1_DP<1>")
		)
		(pad "G22" smd circle
			(at -19.221958 -22.131274)
			(size 0.4318 0.4318)
			(layers "F.Cu" "F.Mask" "F.Paste")
			(net "GND")
		)
		(pad "G24" smd circle
			(at -17.504918 -22.131274)
			(size 0.4318 0.4318)
			(layers "F.Cu" "F.Mask" "F.Paste")
			(net "GND")
		)
		(pad "G26" smd circle
			(at -15.787878 -22.131274)
			(size 0.4318 0.4318)
			(layers "F.Cu" "F.Mask" "F.Paste")
			(net "GND")
		)
		(pad "G28" smd circle
			(at -14.071092 -22.131274)
			(size 0.4318 0.4318)
			(layers "F.Cu" "F.Mask" "F.Paste")
			(net "M_B_DQS_DN<6>")
		)
		(pad "G30" smd circle
			(at -12.354052 -22.131274)
			(size 0.4318 0.4318)
			(layers "F.Cu" "F.Mask" "F.Paste")
			(net "GND")
		)
		(pad "G32" smd circle
			(at -10.637012 -22.131274)
			(size 0.4318 0.4318)
			(layers "F.Cu" "F.Mask" "F.Paste")
			(net "GND")
		)
		(pad "G34" smd circle
			(at -8.919972 -22.131274)
			(size 0.4318 0.4318)
			(layers "F.Cu" "F.Mask" "F.Paste")
			(net "M_B_DQS_DN<5>")
		)
		(pad "G36" smd circle
			(at -7.202932 -22.131274)
			(size 0.4318 0.4318)
			(layers "F.Cu" "F.Mask" "F.Paste")
			(net "GND")
		)
		(pad "G38" smd circle
			(at -5.485892 -22.131274)
			(size 0.4318 0.4318)
			(layers "F.Cu" "F.Mask" "F.Paste")
			(net "GND")
		)
		(pad "G40" smd circle
			(at -3.769106 -22.131274)
			(size 0.4318 0.4318)
			(layers "F.Cu" "F.Mask" "F.Paste")
			(net "M_A_DQS_DN<4>")
		)
		(pad "G42" smd circle
			(at -2.052066 -22.131274)
			(size 0.4318 0.4318)
			(layers "F.Cu" "F.Mask" "F.Paste")
			(net "GND")
		)
		(pad "G46" smd circle
			(at 2.910586 -23.931626)
			(size 0.4318 0.4318)
			(layers "F.Cu" "F.Mask" "F.Paste")
			(net "M_A_C<2>")
		)
		(pad "G48" smd circle
			(at 4.627626 -23.931626)
			(size 0.4318 0.4318)
			(layers "F.Cu" "F.Mask" "F.Paste")
			(net "M_A_ODT<3>")
		)
		(pad "G50" smd circle
			(at 6.344412 -23.931626)
			(size 0.4318 0.4318)
			(layers "F.Cu" "F.Mask" "F.Paste")
			(net "M_A_ODT<2>")
		)
		(pad "G52" smd circle
			(at 8.061452 -23.931626)
			(size 0.4318 0.4318)
			(layers "F.Cu" "F.Mask" "F.Paste")
			(net "M_A_CS_N<0>")
		)
		(pad "G54" smd circle
			(at 9.778492 -23.931626)
			(size 0.4318 0.4318)
			(layers "F.Cu" "F.Mask" "F.Paste")
			(net "M_A_BA<1>")
		)
		(pad "G56" smd circle
			(at 11.495532 -23.931626)
			(size 0.4318 0.4318)
			(layers "F.Cu" "F.Mask" "F.Paste")
			(net "M_A_CLK_DP<2>")
		)
		(pad "G58" smd circle
			(at 13.212572 -23.931626)
			(size 0.4318 0.4318)
			(layers "F.Cu" "F.Mask" "F.Paste")
			(net "M_A_MA<4>")
		)
		(pad "G60" smd circle
			(at 14.929612 -23.931626)
			(size 0.4318 0.4318)
			(layers "F.Cu" "F.Mask" "F.Paste")
			(net "M_A_MA<7>")
		)
		(pad "G62" smd circle
			(at 16.646398 -23.931626)
			(size 0.4318 0.4318)
			(layers "F.Cu" "F.Mask" "F.Paste")
			(net "M_A_MA<11>")
		)
		(pad "G64" smd circle
			(at 18.363438 -23.931626)
			(size 0.4318 0.4318)
			(layers "F.Cu" "F.Mask" "F.Paste")
			(net "TP_CPU0_RSVD_274")
		)
		(pad "G66" smd circle
			(at 20.080478 -23.931626)
			(size 0.4318 0.4318)
			(layers "F.Cu" "F.Mask" "F.Paste")
			(net "GND")
		)
		(pad "G68" smd circle
			(at 21.797518 -23.931626)
			(size 0.4318 0.4318)
			(layers "F.Cu" "F.Mask" "F.Paste")
			(net "M_B_DQS_DN<17>")
		)
		(pad "G70" smd circle
			(at 23.514558 -23.931626)
			(size 0.4318 0.4318)
			(layers "F.Cu" "F.Mask" "F.Paste")
			(net "GND")
		)
		(pad "G72" smd circle
			(at 25.231598 -23.931626)
			(size 0.4318 0.4318)
			(layers "F.Cu" "F.Mask" "F.Paste")
			(net "M_B_DQ<31>")
		)
		(pad "G74" smd circle
			(at 26.948384 -23.931626)
			(size 0.4318 0.4318)
			(layers "F.Cu" "F.Mask" "F.Paste")
			(net "M_B_DQ<29>")
		)
		(pad "G76" smd circle
			(at 28.665424 -23.931626)
			(size 0.4318 0.4318)
			(layers "F.Cu" "F.Mask" "F.Paste")
			(net "GND")
		)
		(pad "G78" smd circle
			(at 30.382464 -23.931626)
			(size 0.4318 0.4318)
			(layers "F.Cu" "F.Mask" "F.Paste")
			(net "GND")
		)
		(pad "G80" smd circle
			(at 32.099504 -23.931626)
			(size 0.4318 0.4318)
			(layers "F.Cu" "F.Mask" "F.Paste")
			(net "GND")
		)
		(pad "G82" smd circle
			(at 33.816544 -23.931626)
			(size 0.4318 0.4318)
			(layers "F.Cu" "F.Mask" "F.Paste")
			(net "GND")
		)
		(pad "G84" smd custom
			(at 35.533584 -23.931626 270)
			(size 0.10795 0.10795)
			(layers "F.Cu" "F.Mask" "F.Paste")
			(net "TP_CPU0_RSVD_273")
			(options
				(clearance outline)
				(anchor circle)
			)
			(primitives
				(gr_poly
					(pts
						(arc
							(start 0.2159 -0.0381)
							(mid 0 -0.254)
							(end -0.2159 -0.0381)
						)
						(arc
							(start -0.2159 0.0381)
							(mid 0 0.254)
							(end 0.2159 0.0381)
						)
					)
					(width 0)
					(fill yes)
				)
			)
		)
		(pad "H1" smd custom
			(at -37.250624 -21.636228 90)
			(size 0.10795 0.10795)
			(layers "F.Cu" "F.Mask" "F.Paste")
			(net "TP_CPU0_RSVD_272")
			(options
				(clearance outline)
				(anchor circle)
			)
			(primitives
				(gr_poly
					(pts
						(arc
							(start 0.2159 -0.0381)
							(mid 0 -0.254)
							(end -0.2159 -0.0381)
						)
						(arc
							(start -0.2159 0.0381)
							(mid 0 0.254)
							(end 0.2159 0.0381)
						)
					)
					(width 0)
					(fill yes)
				)
			)
		)
		(pad "H3" smd circle
			(at -35.533584 -21.636228)
			(size 0.4318 0.4318)
			(layers "F.Cu" "F.Mask" "F.Paste")
			(net "GND")
		)
		(pad "H5" smd circle
			(at -33.816544 -21.636228)
			(size 0.4318 0.4318)
			(layers "F.Cu" "F.Mask" "F.Paste")
			(net "UPI_CPU0_CPU1_P1P1_DP<16>")
		)
		(pad "H7" smd circle
			(at -32.099504 -21.636228)
			(size 0.4318 0.4318)
			(layers "F.Cu" "F.Mask" "F.Paste")
			(net "UPI_CPU0_CPU1_P1P1_DN<14>")
		)
		(pad "H9" smd circle
			(at -30.382464 -21.636228)
			(size 0.4318 0.4318)
			(layers "F.Cu" "F.Mask" "F.Paste")
			(net "UPI_CPU0_CPU1_P1P1_DP<10>")
		)
		(pad "H11" smd circle
			(at -28.665424 -21.636228)
			(size 0.4318 0.4318)
			(layers "F.Cu" "F.Mask" "F.Paste")
			(net "GND")
		)
		(pad "H13" smd circle
			(at -26.948384 -21.636228)
			(size 0.4318 0.4318)
			(layers "F.Cu" "F.Mask" "F.Paste")
			(net "PVCCIO_CPU0")
		)
		(pad "H15" smd circle
			(at -25.231598 -21.636228)
			(size 0.4318 0.4318)
			(layers "F.Cu" "F.Mask" "F.Paste")
			(net "UPI_CPU0_CPU1_P1P1_DP<6>")
		)
		(pad "H17" smd circle
			(at -23.514558 -21.636228)
			(size 0.4318 0.4318)
			(layers "F.Cu" "F.Mask" "F.Paste")
			(net "UPI_CPU0_CPU1_P1P1_DN<5>")
		)
		(pad "H19" smd circle
			(at -21.797518 -21.636228)
			(size 0.4318 0.4318)
			(layers "F.Cu" "F.Mask" "F.Paste")
			(net "UPI_CPU0_CPU1_P1P1_DP<2>")
		)
		(pad "H21" smd circle
			(at -20.080478 -21.636228)
			(size 0.4318 0.4318)
			(layers "F.Cu" "F.Mask" "F.Paste")
			(net "UPI_CPU0_CPU1_P1P1_DN<0>")
		)
		(pad "H23" smd circle
			(at -18.363438 -21.636228)
			(size 0.4318 0.4318)
			(layers "F.Cu" "F.Mask" "F.Paste")
			(net "M_A_DQ<62>")
		)
		(pad "H25" smd circle
			(at -16.646398 -21.636228)
			(size 0.4318 0.4318)
			(layers "F.Cu" "F.Mask" "F.Paste")
			(net "GND")
		)
		(pad "H27" smd circle
			(at -14.929612 -21.636228)
			(size 0.4318 0.4318)
			(layers "F.Cu" "F.Mask" "F.Paste")
			(net "GND")
		)
		(pad "H29" smd circle
			(at -13.212572 -21.636228)
			(size 0.4318 0.4318)
			(layers "F.Cu" "F.Mask" "F.Paste")
			(net "GND")
		)
		(pad "H31" smd circle
			(at -11.495532 -21.636228)
			(size 0.4318 0.4318)
			(layers "F.Cu" "F.Mask" "F.Paste")
			(net "GND")
		)
		(pad "H33" smd circle
			(at -9.778492 -21.636228)
			(size 0.4318 0.4318)
			(layers "F.Cu" "F.Mask" "F.Paste")
			(net "GND")
		)
		(pad "H35" smd circle
			(at -8.061452 -21.636228)
			(size 0.4318 0.4318)
			(layers "F.Cu" "F.Mask" "F.Paste")
			(net "GND")
		)
		(pad "H37" smd circle
			(at -6.344412 -21.636228)
			(size 0.4318 0.4318)
			(layers "F.Cu" "F.Mask" "F.Paste")
			(net "GND")
		)
		(pad "H39" smd circle
			(at -4.627626 -21.636228)
			(size 0.4318 0.4318)
			(layers "F.Cu" "F.Mask" "F.Paste")
			(net "GND")
		)
		(pad "H41" smd circle
			(at -2.910586 -21.636228)
			(size 0.4318 0.4318)
			(layers "F.Cu" "F.Mask" "F.Paste")
			(net "GND")
		)
		(pad "H43" smd circle
			(at -1.193546 -21.636228)
			(size 0.4318 0.4318)
			(layers "F.Cu" "F.Mask" "F.Paste")
			(net "M_B_DQ<33>")
		)
		(pad "H45" smd circle
			(at 2.052066 -23.436326)
			(size 0.508 0.508)
			(layers "F.Cu" "F.Mask" "F.Paste")
			(net "GND")
		)
		(pad "H47" smd circle
			(at 3.769106 -23.436326)
			(size 0.4318 0.4318)
			(layers "F.Cu" "F.Mask" "F.Paste")
			(net "GND")
		)
		(pad "H49" smd circle
			(at 5.485892 -23.436326)
			(size 0.4318 0.4318)
			(layers "F.Cu" "F.Mask" "F.Paste")
			(net "GND")
		)
		(pad "H51" smd circle
			(at 7.202932 -23.436326)
			(size 0.4318 0.4318)
			(layers "F.Cu" "F.Mask" "F.Paste")
			(net "GND")
		)
		(pad "H53" smd circle
			(at 8.919972 -23.436326)
			(size 0.4318 0.4318)
			(layers "F.Cu" "F.Mask" "F.Paste")
			(net "GND")
		)
		(pad "H55" smd circle
			(at 10.637012 -23.436326)
			(size 0.4318 0.4318)
			(layers "F.Cu" "F.Mask" "F.Paste")
			(net "GND")
		)
		(pad "H57" smd circle
			(at 12.354052 -23.436326)
			(size 0.4318 0.4318)
			(layers "F.Cu" "F.Mask" "F.Paste")
			(net "GND")
		)
		(pad "H59" smd circle
			(at 14.071092 -23.436326)
			(size 0.4318 0.4318)
			(layers "F.Cu" "F.Mask" "F.Paste")
			(net "GND")
		)
		(pad "H61" smd circle
			(at 15.787878 -23.436326)
			(size 0.4318 0.4318)
			(layers "F.Cu" "F.Mask" "F.Paste")
			(net "GND")
		)
		(pad "H63" smd circle
			(at 17.504918 -23.436326)
			(size 0.4318 0.4318)
			(layers "F.Cu" "F.Mask" "F.Paste")
			(net "GND")
		)
		(pad "H65" smd circle
			(at 19.221958 -23.436326)
			(size 0.4318 0.4318)
			(layers "F.Cu" "F.Mask" "F.Paste")
			(net "GND")
		)
		(pad "H67" smd circle
			(at 20.938998 -23.436326)
			(size 0.4318 0.4318)
			(layers "F.Cu" "F.Mask" "F.Paste")
			(net "M_B_ECC<6>")
		)
		(pad "H69" smd circle
			(at 22.656038 -23.436326)
			(size 0.4318 0.4318)
			(layers "F.Cu" "F.Mask" "F.Paste")
			(net "M_B_ECC<1>")
		)
		(pad "H71" smd circle
			(at 24.373078 -23.436326)
			(size 0.4318 0.4318)
			(layers "F.Cu" "F.Mask" "F.Paste")
			(net "GND")
		)
		(pad "H73" smd circle
			(at 26.090118 -23.436326)
			(size 0.4318 0.4318)
			(layers "F.Cu" "F.Mask" "F.Paste")
			(net "M_B_DQS_DN<3>")
		)
		(pad "H75" smd circle
			(at 27.806904 -23.436326)
			(size 0.4318 0.4318)
			(layers "F.Cu" "F.Mask" "F.Paste")
			(net "GND")
		)
		(pad "H77" smd circle
			(at 29.523944 -23.436326)
			(size 0.4318 0.4318)
			(layers "F.Cu" "F.Mask" "F.Paste")
			(net "M_B_DQ<19>")
		)
		(pad "H79" smd circle
			(at 31.240984 -23.436326)
			(size 0.4318 0.4318)
			(layers "F.Cu" "F.Mask" "F.Paste")
			(net "M_B_DQS_DP<2>")
		)
		(pad "H81" smd circle
			(at 32.958024 -23.436326)
			(size 0.4318 0.4318)
			(layers "F.Cu" "F.Mask" "F.Paste")
			(net "M_B_DQ<21>")
		)
		(pad "H83" smd circle
			(at 34.675064 -23.436326)
			(size 0.4318 0.4318)
			(layers "F.Cu" "F.Mask" "F.Paste")
			(net "TP_CPU0_RSVD_271")
		)
		(pad "H85" smd custom
			(at 36.392104 -23.436326 270)
			(size 0.10795 0.10795)
			(layers "F.Cu" "F.Mask" "F.Paste")
			(net "TP_CPU0_RSVD_270")
			(options
				(clearance outline)
				(anchor circle)
			)
			(primitives
				(gr_poly
					(pts
						(arc
							(start 0.2159 -0.0381)
							(mid 0 -0.254)
							(end -0.2159 -0.0381)
						)
						(arc
							(start -0.2159 0.0381)
							(mid 0 0.254)
							(end 0.2159 0.0381)
						)
					)
					(width 0)
					(fill yes)
				)
			)
		)
		(pad "J2" smd circle
			(at -36.392104 -21.140674)
			(size 0.4318 0.4318)
			(layers "F.Cu" "F.Mask" "F.Paste")
			(net "PVCCIO_CPU0")
		)
		(pad "J4" smd circle
			(at -34.675064 -21.140674)
			(size 0.4318 0.4318)
			(layers "F.Cu" "F.Mask" "F.Paste")
			(net "GND")
		)
		(pad "J6" smd circle
			(at -32.958024 -21.140674)
			(size 0.4318 0.4318)
			(layers "F.Cu" "F.Mask" "F.Paste")
			(net "UPI_CPU0_CPU1_P1P1_DN<16>")
		)
		(pad "J8" smd circle
			(at -31.240984 -21.140674)
			(size 0.4318 0.4318)
			(layers "F.Cu" "F.Mask" "F.Paste")
			(net "UPI_CPU0_CPU1_P1P1_DP<13>")
		)
		(pad "J10" smd circle
			(at -29.523944 -21.140674)
			(size 0.4318 0.4318)
			(layers "F.Cu" "F.Mask" "F.Paste")
			(net "PVCCIO_CPU0")
		)
		(pad "J12" smd circle
			(at -27.806904 -21.140674)
			(size 0.4318 0.4318)
			(layers "F.Cu" "F.Mask" "F.Paste")
			(net "GND")
		)
		(pad "J14" smd circle
			(at -26.090118 -21.140674)
			(size 0.4318 0.4318)
			(layers "F.Cu" "F.Mask" "F.Paste")
			(net "GND")
		)
		(pad "J16" smd circle
			(at -24.373078 -21.140674)
			(size 0.4318 0.4318)
			(layers "F.Cu" "F.Mask" "F.Paste")
			(net "GND")
		)
		(pad "J18" smd circle
			(at -22.656038 -21.140674)
			(size 0.4318 0.4318)
			(layers "F.Cu" "F.Mask" "F.Paste")
			(net "UPI_CPU0_CPU1_P1P1_DP<3>")
		)
		(pad "J20" smd circle
			(at -20.938998 -21.140674)
			(size 0.4318 0.4318)
			(layers "F.Cu" "F.Mask" "F.Paste")
			(net "UPI_CPU0_CPU1_P1P1_DN<2>")
		)
		(pad "J22" smd circle
			(at -19.221958 -21.140674)
			(size 0.4318 0.4318)
			(layers "F.Cu" "F.Mask" "F.Paste")
			(net "GND")
		)
		(pad "J24" smd circle
			(at -17.504918 -21.140674)
			(size 0.4318 0.4318)
			(layers "F.Cu" "F.Mask" "F.Paste")
			(net "M_A_DQS_DN<16>")
		)
		(pad "J26" smd circle
			(at -15.787878 -21.140674)
			(size 0.4318 0.4318)
			(layers "F.Cu" "F.Mask" "F.Paste")
			(net "GND")
		)
		(pad "J28" smd circle
			(at -14.071092 -21.140674)
			(size 0.4318 0.4318)
			(layers "F.Cu" "F.Mask" "F.Paste")
			(net "GND")
		)
	)
)
